(kicad_pcb
	(version 20260206)
	(generator "pcbnew")
	(generator_version "10.0")
	(general
		(thickness 1.6)
		(legacy_teardrops no)
	)
	(paper "A4")
	(title_block
		(title "Bryce Canyon_IOM_IOC_16318-2_OCP.brd")
		(comment 1 "Bryce Canyon / footprints 1004-1011 of 1605")
	)
	(layers
		(0 "F.Cu" signal "TOP")
		(4 "In1.Cu" signal "L2GND")
		(6 "In2.Cu" signal "L3")
		(8 "In3.Cu" signal "L4VCC")
		(10 "In4.Cu" signal "L5VCC")
		(12 "In5.Cu" signal "L6")
		(14 "In6.Cu" signal "L7GND")
		(2 "B.Cu" signal "BOTTOM")
		(9 "F.Adhes" user "F.Adhesive")
		(11 "B.Adhes" user "B.Adhesive")
		(13 "F.Paste" user "Package Geometry/Pastemask Top")
		(15 "B.Paste" user "Package Geometry/Pastemask Bottom")
		(5 "F.SilkS" user "Ref Des/Silkscreen Top")
		(7 "B.SilkS" user "Ref Des/Silkscreen Bottom")
		(1 "F.Mask" user "Board Geometry/Soldermask Top")
		(3 "B.Mask" user "Board Geometry/Soldermask Bottom")
		(17 "Dwgs.User" user "User.Drawings")
		(19 "Cmts.User" user "User.Comments")
		(21 "Eco1.User" user "User.Eco1")
		(23 "Eco2.User" user "User.Eco2")
		(25 "Edge.Cuts" user "Board Geometry/Outline")
		(27 "Margin" user)
		(31 "F.CrtYd" user "Package Geometry/Place Bound Top")
		(29 "B.CrtYd" user "Package Geometry/Place Bound Bottom")
		(35 "F.Fab" user "Ref Des/Assembly Top")
		(33 "B.Fab" user "Ref Des/Assembly Bottom")
	)
	(footprint ""
		(layer "B.Cu")
		(at 23.440644 -131.007358 180)
		(property "Reference" "R249"
			(at 0 0 0)
			(layer "B.SilkS")
			(hide yes)
			(effects
				(font
					(size 1.27 1.27)
				)
				(justify mirror)
			)
		)
		(property "Value" "120R2F-GP"
			(at -0.064008 -3.993896 180)
			(unlocked yes)
			(layer "B.Fab")
			(hide yes)
			(effects
				(font
					(size 1.016 1.016)
					(thickness 0.1524)
				)
				(justify mirror)
			)
		)
		(property "Device Type" "R402H16"
			(at -0.064008 -5.517896 180)
			(unlocked yes)
			(layer "B.Fab")
			(hide yes)
			(effects
				(font
					(size 1.016 1.016)
					(thickness 0.1524)
				)
				(justify mirror)
			)
		)
		(duplicate_pad_numbers_are_jumpers no)
		(fp_line
			(start 0.508 -0.9398)
			(end 0.508 0.9398)
			(stroke
				(width 0.1524)
				(type default)
			)
			(layer "B.SilkS")
		)
		(fp_line
			(start -0.508 -0.9398)
			(end 0.508 -0.9398)
			(stroke
				(width 0.1524)
				(type default)
			)
			(layer "B.SilkS")
		)
		(fp_rect
			(start 0.508 0.9398)
			(end -0.508 -0.9398)
			(stroke
				(width 0)
				(type default)
			)
			(fill no)
			(layer "B.CrtYd")
		)
		(fp_rect
			(start 0.508 0.9398)
			(end -0.508 -0.9398)
			(stroke
				(width 0)
				(type default)
			)
			(fill no)
			(layer "B.Fab")
		)
		(pad "1" smd custom
			(at 0 -0.4445)
			(size 0.1397 0.1397)
			(layers "B.Cu" "B.Mask" "B.Paste")
			(net "MEMA_7")
			(options
				(clearance outline)
				(anchor circle)
			)
			(primitives
				(gr_poly
					(pts
						(arc
							(start -0.1778 0.2794)
							(mid -0.249642 0.249642)
							(end -0.2794 0.1778)
						)
						(arc
							(start -0.2794 -0.1778)
							(mid -0.249642 -0.249642)
							(end -0.1778 -0.2794)
						)
						(arc
							(start 0.1778 -0.2794)
							(mid 0.249642 -0.249642)
							(end 0.2794 -0.1778)
						)
						(arc
							(start 0.2794 0.1778)
							(mid 0.249642 0.249642)
							(end 0.1778 0.2794)
						)
					)
					(width 0)
					(fill yes)
				)
			)
		)
		(pad "2" smd custom
			(at 0 0.4445)
			(size 0.1397 0.1397)
			(layers "B.Cu" "B.Mask" "B.Paste")
			(net "P1V2_STBY")
			(options
				(clearance outline)
				(anchor circle)
			)
			(primitives
				(gr_poly
					(pts
						(arc
							(start -0.1778 0.2794)
							(mid -0.249642 0.249642)
							(end -0.2794 0.1778)
						)
						(arc
							(start -0.2794 -0.1778)
							(mid -0.249642 -0.249642)
							(end -0.1778 -0.2794)
						)
						(arc
							(start 0.1778 -0.2794)
							(mid 0.249642 -0.249642)
							(end 0.2794 -0.1778)
						)
						(arc
							(start 0.2794 0.1778)
							(mid 0.249642 0.249642)
							(end 0.1778 0.2794)
						)
					)
					(width 0)
					(fill yes)
				)
			)
		)
	)
	(footprint ""
		(layer "B.Cu")
		(at 36.585398 -140.280644)
		(property "Reference" "C104"
			(at 0 0 0)
			(layer "B.SilkS")
			(hide yes)
			(effects
				(font
					(size 1.27 1.27)
				)
				(justify mirror)
			)
		)
		(property "Value" "SC10U6D3V3KX-1-GP"
			(at 0 -2.8194 0)
			(unlocked yes)
			(layer "B.Fab")
			(hide yes)
			(effects
				(font
					(size 1.016 1.016)
					(thickness 0.1524)
				)
				(justify mirror)
			)
		)
		(property "Device Type" "C603H40"
			(at 0 -4.3434 0)
			(unlocked yes)
			(layer "B.Fab")
			(hide yes)
			(effects
				(font
					(size 1.016 1.016)
					(thickness 0.1524)
				)
				(justify mirror)
			)
		)
		(duplicate_pad_numbers_are_jumpers no)
		(fp_line
			(start -0.508 0)
			(end 0.508 0)
			(stroke
				(width 0.2032)
				(type default)
			)
			(layer "B.SilkS")
		)
		(fp_rect
			(start 0.5842 1.3335)
			(end -0.5842 -1.3335)
			(stroke
				(width 0)
				(type default)
			)
			(fill no)
			(layer "B.CrtYd")
		)
		(fp_rect
			(start 0.5842 1.3335)
			(end -0.5842 -1.3335)
			(stroke
				(width 0)
				(type default)
			)
			(fill no)
			(layer "B.Fab")
		)
		(pad "1" smd custom
			(at 0 -0.762 180)
			(size 0.2159 0.2159)
			(layers "B.Cu" "B.Mask" "B.Paste")
			(net "GND")
			(options
				(clearance outline)
				(anchor circle)
			)
			(primitives
				(gr_poly
					(pts
						(arc
							(start -0.3302 0.4318)
							(mid -0.402042 0.402042)
							(end -0.4318 0.3302)
						)
						(arc
							(start -0.4318 -0.3302)
							(mid -0.402042 -0.402042)
							(end -0.3302 -0.4318)
						)
						(arc
							(start 0.3302 -0.4318)
							(mid 0.402042 -0.402042)
							(end 0.4318 -0.3302)
						)
						(arc
							(start 0.4318 0.3302)
							(mid 0.402042 0.402042)
							(end 0.3302 0.4318)
						)
					)
					(width 0)
					(fill yes)
				)
			)
		)
		(pad "2" smd custom
			(at 0 0.762 180)
			(size 0.2159 0.2159)
			(layers "B.Cu" "B.Mask" "B.Paste")
			(net "P3V3_STBY")
			(options
				(clearance outline)
				(anchor circle)
			)
			(primitives
				(gr_poly
					(pts
						(arc
							(start -0.3302 0.4318)
							(mid -0.402042 0.402042)
							(end -0.4318 0.3302)
						)
						(arc
							(start -0.4318 -0.3302)
							(mid -0.402042 -0.402042)
							(end -0.3302 -0.4318)
						)
						(arc
							(start 0.3302 -0.4318)
							(mid 0.402042 -0.402042)
							(end 0.4318 -0.3302)
						)
						(arc
							(start 0.4318 0.3302)
							(mid 0.402042 0.402042)
							(end 0.3302 0.4318)
						)
					)
					(width 0)
					(fill yes)
				)
			)
		)
	)
	(footprint ""
		(layer "B.Cu")
		(at 43.3832 -128.2192)
		(property "Reference" "R270"
			(at 0 0 0)
			(layer "B.SilkS")
			(hide yes)
			(effects
				(font
					(size 1.27 1.27)
				)
				(justify mirror)
			)
		)
		(property "Value" "33R2F-3-GP"
			(at -0.064008 -3.993896 0)
			(unlocked yes)
			(layer "B.Fab")
			(hide yes)
			(effects
				(font
					(size 1.016 1.016)
					(thickness 0.1524)
				)
				(justify mirror)
			)
		)
		(property "Device Type" "R402H16"
			(at -0.064008 -5.517896 0)
			(unlocked yes)
			(layer "B.Fab")
			(hide yes)
			(effects
				(font
					(size 1.016 1.016)
					(thickness 0.1524)
				)
				(justify mirror)
			)
		)
		(duplicate_pad_numbers_are_jumpers no)
		(fp_line
			(start -0.508 -0.9398)
			(end 0.508 -0.9398)
			(stroke
				(width 0.1524)
				(type default)
			)
			(layer "B.SilkS")
		)
		(fp_line
			(start 0.508 -0.9398)
			(end 0.508 0.9398)
			(stroke
				(width 0.1524)
				(type default)
			)
			(layer "B.SilkS")
		)
		(fp_rect
			(start 0.508 0.9398)
			(end -0.508 -0.9398)
			(stroke
				(width 0)
				(type default)
			)
			(fill no)
			(layer "B.CrtYd")
		)
		(fp_rect
			(start 0.508 0.9398)
			(end -0.508 -0.9398)
			(stroke
				(width 0)
				(type default)
			)
			(fill no)
			(layer "B.Fab")
		)
		(pad "1" smd custom
			(at 0 -0.4445 180)
			(size 0.1397 0.1397)
			(layers "B.Cu" "B.Mask" "B.Paste")
			(net "BMC_SPI_MISO")
			(options
				(clearance outline)
				(anchor circle)
			)
			(primitives
				(gr_poly
					(pts
						(arc
							(start -0.1778 0.2794)
							(mid -0.249642 0.249642)
							(end -0.2794 0.1778)
						)
						(arc
							(start -0.2794 -0.1778)
							(mid -0.249642 -0.249642)
							(end -0.1778 -0.2794)
						)
						(arc
							(start 0.1778 -0.2794)
							(mid 0.249642 -0.249642)
							(end 0.2794 -0.1778)
						)
						(arc
							(start 0.2794 0.1778)
							(mid 0.249642 0.249642)
							(end 0.1778 0.2794)
						)
					)
					(width 0)
					(fill yes)
				)
			)
		)
		(pad "2" smd custom
			(at 0 0.4445 180)
			(size 0.1397 0.1397)
			(layers "B.Cu" "B.Mask" "B.Paste")
			(net "BMC_SPI_MISO_R")
			(options
				(clearance outline)
				(anchor circle)
			)
			(primitives
				(gr_poly
					(pts
						(arc
							(start -0.1778 0.2794)
							(mid -0.249642 0.249642)
							(end -0.2794 0.1778)
						)
						(arc
							(start -0.2794 -0.1778)
							(mid -0.249642 -0.249642)
							(end -0.1778 -0.2794)
						)
						(arc
							(start 0.1778 -0.2794)
							(mid 0.249642 -0.249642)
							(end 0.2794 -0.1778)
						)
						(arc
							(start 0.2794 0.1778)
							(mid 0.249642 0.249642)
							(end 0.1778 0.2794)
						)
					)
					(width 0)
					(fill yes)
				)
			)
		)
	)
	(footprint ""
		(layer "B.Cu")
		(at 201.070718 -81.153 180)
		(property "Reference" "C290"
			(at 0 0 0)
			(layer "B.SilkS")
			(hide yes)
			(effects
				(font
					(size 1.27 1.27)
				)
				(justify mirror)
			)
		)
		(property "Value" "SCD22U10V1KX-GP"
			(at 2.8321 -1.7399 180)
			(unlocked yes)
			(layer "B.Fab")
			(hide yes)
			(effects
				(font
					(size 1.016 1.016)
					(thickness 0.1524)
				)
				(justify mirror)
			)
		)
		(property "Device Type" "C0201H13"
			(at 2.8321 -3.2639 180)
			(unlocked yes)
			(layer "B.Fab")
			(hide yes)
			(effects
				(font
					(size 1.016 1.016)
					(thickness 0.1524)
				)
				(justify mirror)
			)
		)
		(duplicate_pad_numbers_are_jumpers no)
		(fp_rect
			(start 0.2794 0.6477)
			(end -0.2794 -0.6477)
			(stroke
				(width 0)
				(type default)
			)
			(fill no)
			(layer "B.CrtYd")
		)
		(fp_rect
			(start 0.2794 0.6477)
			(end -0.2794 -0.6477)
			(stroke
				(width 0)
				(type default)
			)
			(fill no)
			(layer "B.Fab")
		)
		(pad "1" smd custom
			(at 0 -0.2794)
			(size 0.0762 0.0762)
			(layers "B.Cu" "B.Mask" "B.Paste")
			(net "PCIE_IOM_TO_COMP_8_DN_C")
			(options
				(clearance outline)
				(anchor circle)
			)
			(primitives
				(gr_poly
					(pts
						(arc
							(start 0.1524 0.127)
							(mid 0.137521 0.162921)
							(end 0.1016 0.1778)
						)
						(arc
							(start -0.1016 0.1778)
							(mid -0.137521 0.162921)
							(end -0.1524 0.127)
						)
						(arc
							(start -0.1524 -0.127)
							(mid -0.137521 -0.162921)
							(end -0.1016 -0.1778)
						)
						(arc
							(start 0.1016 -0.1778)
							(mid 0.137521 -0.162921)
							(end 0.1524 -0.127)
						)
					)
					(width 0)
					(fill yes)
				)
			)
		)
		(pad "2" smd custom
			(at 0 0.2794)
			(size 0.0762 0.0762)
			(layers "B.Cu" "B.Mask" "B.Paste")
			(net "PCIE_IOM_TO_COMP_8_DN")
			(options
				(clearance outline)
				(anchor circle)
			)
			(primitives
				(gr_poly
					(pts
						(arc
							(start 0.1524 0.127)
							(mid 0.137521 0.162921)
							(end 0.1016 0.1778)
						)
						(arc
							(start -0.1016 0.1778)
							(mid -0.137521 0.162921)
							(end -0.1524 0.127)
						)
						(arc
							(start -0.1524 -0.127)
							(mid -0.137521 -0.162921)
							(end -0.1016 -0.1778)
						)
						(arc
							(start 0.1016 -0.1778)
							(mid 0.137521 -0.162921)
							(end 0.1524 -0.127)
						)
					)
					(width 0)
					(fill yes)
				)
			)
		)
	)
	(footprint ""
		(layer "B.Cu")
		(at 97.62871 -153.851102 45)
		(property "Reference" "TP6"
			(at 0 0 45)
			(layer "B.SilkS")
			(hide yes)
			(effects
				(font
					(size 1.27 1.27)
				)
				(justify mirror)
			)
		)
		(property "Value" "TPAD28-2-GP"
			(at 0.012752 -1.663607 45)
			(unlocked yes)
			(layer "B.Fab")
			(hide yes)
			(effects
				(font
					(size 1.016 1.016)
					(thickness 0.1524)
				)
				(justify mirror)
			)
		)
		(property "Device Type" "TPAD28"
			(at 0.012752 -3.187736 45)
			(unlocked yes)
			(layer "B.Fab")
			(hide yes)
			(effects
				(font
					(size 1.016 1.016)
					(thickness 0.1524)
				)
				(justify mirror)
			)
		)
		(duplicate_pad_numbers_are_jumpers no)
		(fp_poly
			(pts
				(arc
					(start 0.251447 0.251447)
					(mid -0.251447 -0.251447)
					(end 0.251447 0.251447)
				)
			)
			(stroke
				(width 0)
				(type default)
			)
			(fill no)
			(layer "B.CrtYd")
		)
		(fp_poly
			(pts
				(arc
					(start 0.431052 0.431052)
					(mid -0.431052 -0.431052)
					(end 0.431052 0.431052)
				)
			)
			(stroke
				(width 0)
				(type default)
			)
			(fill no)
			(layer "B.Fab")
		)
		(pad "1" smd circle
			(at 0 0 225)
			(size 0.7112 0.7112)
			(layers "B.Cu" "B.Mask" "B.Paste")
			(net "TP_USB_SDA")
		)
	)
	(footprint ""
		(layer "B.Cu")
		(at 194.279266 -72.380856 -90)
		(property "Reference" "C358"
			(at 0 0 90)
			(layer "B.SilkS")
			(hide yes)
			(effects
				(font
					(size 1.27 1.27)
				)
				(justify mirror)
			)
		)
		(property "Value" "SC1U6D3V1MX-GP"
			(at -1.9177 2.0193 270)
			(unlocked yes)
			(layer "B.Fab")
			(hide yes)
			(effects
				(font
					(size 1.016 1.016)
					(thickness 0.1524)
				)
				(justify mirror)
			)
		)
		(property "Device Type" "C0201H14"
			(at -1.9177 0.4953 270)
			(unlocked yes)
			(layer "B.Fab")
			(hide yes)
			(effects
				(font
					(size 1.016 1.016)
					(thickness 0.1524)
				)
				(justify mirror)
			)
		)
		(duplicate_pad_numbers_are_jumpers no)
		(fp_rect
			(start 0.1524 0.3048)
			(end -0.1524 -0.3048)
			(stroke
				(width 0)
				(type default)
			)
			(fill no)
			(layer "B.CrtYd")
		)
		(fp_poly
			(pts
				(xy 0.2794 0.6477) (xy 0.2794 -0.6477) (xy -0.2794 -0.6477) (xy -0.2794 -0.1905) (xy -0.1524 -0.1905)
				(xy -0.1524 -0.3048) (xy 0.1524 -0.3048) (xy 0.1524 0.3048) (xy -0.1524 0.3048) (xy -0.1524 -0.1778)
				(xy -0.2794 -0.1778) (xy -0.2794 0.6477)
			)
			(stroke
				(width 0)
				(type default)
			)
			(fill no)
			(layer "B.CrtYd")
		)
		(fp_rect
			(start 0.2794 0.6477)
			(end -0.2794 -0.6477)
			(stroke
				(width 0)
				(type default)
			)
			(fill no)
			(layer "B.Fab")
		)
		(pad "1" smd custom
			(at 0 -0.2794 90)
			(size 0.0762 0.0762)
			(layers "B.Cu" "B.Mask" "B.Paste")
			(net "PCE_VDDH")
			(options
				(clearance outline)
				(anchor circle)
			)
			(primitives
				(gr_poly
					(pts
						(arc
							(start 0.1524 0.127)
							(mid 0.137521 0.162921)
							(end 0.1016 0.1778)
						)
						(arc
							(start -0.1016 0.1778)
							(mid -0.137521 0.162921)
							(end -0.1524 0.127)
						)
						(arc
							(start -0.1524 -0.127)
							(mid -0.137521 -0.162921)
							(end -0.1016 -0.1778)
						)
						(arc
							(start 0.1016 -0.1778)
							(mid 0.137521 -0.162921)
							(end 0.1524 -0.127)
						)
					)
					(width 0)
					(fill yes)
				)
			)
		)
		(pad "2" smd custom
			(at 0 0.2794 90)
			(size 0.0762 0.0762)
			(layers "B.Cu" "B.Mask" "B.Paste")
			(net "GND")
			(options
				(clearance outline)
				(anchor circle)
			)
			(primitives
				(gr_poly
					(pts
						(arc
							(start 0.1524 0.127)
							(mid 0.137521 0.162921)
							(end 0.1016 0.1778)
						)
						(arc
							(start -0.1016 0.1778)
							(mid -0.137521 0.162921)
							(end -0.1524 0.127)
						)
						(arc
							(start -0.1524 -0.127)
							(mid -0.137521 -0.162921)
							(end -0.1016 -0.1778)
						)
						(arc
							(start 0.1016 -0.1778)
							(mid 0.137521 -0.162921)
							(end 0.1524 -0.127)
						)
					)
					(width 0)
					(fill yes)
				)
			)
		)
	)
	(footprint ""
		(layer "B.Cu")
		(at 48.387 -138.9634)
		(property "Reference" "TP20"
			(at 0 0 0)
			(layer "B.SilkS")
			(hide yes)
			(effects
				(font
					(size 1.27 1.27)
				)
				(justify mirror)
			)
		)
		(property "Value" "TPAD28-2-GP"
			(at 0.0127 -1.6637 0)
			(unlocked yes)
			(layer "B.Fab")
			(hide yes)
			(effects
				(font
					(size 1.016 1.016)
					(thickness 0.1524)
				)
				(justify mirror)
			)
		)
		(property "Device Type" "TPAD28"
			(at 0.0127 -3.1877 0)
			(unlocked yes)
			(layer "B.Fab")
			(hide yes)
			(effects
				(font
					(size 1.016 1.016)
					(thickness 0.1524)
				)
				(justify mirror)
			)
		)
		(duplicate_pad_numbers_are_jumpers no)
		(fp_poly
			(pts
				(arc
					(start 0.3556 0)
					(mid -0.3556 0)
					(end 0.3556 0)
				)
			)
			(stroke
				(width 0)
				(type default)
			)
			(fill no)
			(layer "B.CrtYd")
		)
		(fp_poly
			(pts
				(arc
					(start 0.6096 0)
					(mid -0.6096 0)
					(end 0.6096 0)
				)
			)
			(stroke
				(width 0)
				(type default)
			)
			(fill no)
			(layer "B.Fab")
		)
		(pad "1" smd circle
			(at 0 0 180)
			(size 0.7112 0.7112)
			(layers "B.Cu" "B.Mask" "B.Paste")
			(net "TP_M2_1_ALERT#")
		)
	)
	(footprint ""
		(layer "B.Cu")
		(at 55.9562 -132.5626)
		(property "Reference" "C116"
			(at 0 0 0)
			(layer "B.SilkS")
			(hide yes)
			(effects
				(font
					(size 1.27 1.27)
				)
				(justify mirror)
			)
		)
		(property "Value" "SC4D7U25V5KX-1-GP"
			(at 0.0762 -6.1214 0)
			(unlocked yes)
			(layer "B.Fab")
			(hide yes)
			(effects
				(font
					(size 1.016 1.016)
					(thickness 0.1524)
				)
				(justify mirror)
			)
		)
		(property "Device Type" "C805H58"
			(at 0.0762 -8.1534 0)
			(unlocked yes)
			(layer "B.Fab")
			(hide yes)
			(effects
				(font
					(size 1.016 1.016)
					(thickness 0.1524)
				)
				(justify mirror)
			)
		)
		(duplicate_pad_numbers_are_jumpers no)
		(fp_line
			(start -0.635 0)
			(end 0.635 0)
			(stroke
				(width 0.508)
				(type default)
			)
			(layer "B.SilkS")
		)
		(fp_rect
			(start 0.9652 1.778)
			(end -0.9652 -1.778)
			(stroke
				(width 0)
				(type default)
			)
			(fill no)
			(layer "B.CrtYd")
		)
		(fp_poly
			(pts
				(xy 0.9652 -1.778) (xy -0.9652 -1.778) (xy -0.9652 1.778) (xy 0.9652 1.778)
			)
			(stroke
				(width 0)
				(type default)
			)
			(fill no)
			(layer "B.Fab")
		)
		(pad "1" smd rect
			(at 0 -0.9652 180)
			(size 1.397 1.143)
			(layers "B.Cu" "B.Mask" "B.Paste")
			(net "P1V15_STBY")
		)
		(pad "2" smd rect
			(at 0 0.9652 180)
			(size 1.397 1.143)
			(layers "B.Cu" "B.Mask" "B.Paste")
			(net "GND")
		)
	)
)
